(kicad_pcb
	(version 20260206)
	(generator "pcbnew")
	(generator_version "10.0")
	(general
		(thickness 1.6)
		(legacy_teardrops no)
	)
	(paper "A4")
	(title_block
		(title "Wiwynn_Tioga_Pass_MB.brd")
		(comment 1 "Tioga Pass / footprints 2573-2579 of 4770")
	)
	(layers
		(0 "F.Cu" signal "TOP")
		(4 "In1.Cu" signal "L2GND")
		(6 "In2.Cu" signal "L3")
		(8 "In3.Cu" signal "L4GND")
		(10 "In4.Cu" signal "L5")
		(12 "In5.Cu" signal "L6GND")
		(14 "In6.Cu" signal "L7VCC")
		(16 "In7.Cu" signal "L8VCC")
		(18 "In8.Cu" signal "L9GND")
		(20 "In9.Cu" signal "L10")
		(22 "In10.Cu" signal "L11GND")
		(24 "In11.Cu" signal "L12")
		(26 "In12.Cu" signal "L13GND")
		(2 "B.Cu" signal "BOTTOM")
		(9 "F.Adhes" user "F.Adhesive")
		(11 "B.Adhes" user "B.Adhesive")
		(13 "F.Paste" user "Package Geometry/Pastemask Top")
		(15 "B.Paste" user "Package Geometry/Pastemask Bottom")
		(5 "F.SilkS" user "Ref Des/Silkscreen Top")
		(7 "B.SilkS" user "Ref Des/Silkscreen Bottom")
		(1 "F.Mask" user "Board Geometry/Soldermask Top")
		(3 "B.Mask" user "Board Geometry/Soldermask Bottom")
		(17 "Dwgs.User" user "User.Drawings")
		(19 "Cmts.User" user "User.Comments")
		(21 "Eco1.User" user "User.Eco1")
		(23 "Eco2.User" user "User.Eco2")
		(25 "Edge.Cuts" user "Board Geometry/Outline")
		(27 "Margin" user)
		(31 "F.CrtYd" user "Package Geometry/Place Bound Top")
		(29 "B.CrtYd" user "Package Geometry/Place Bound Bottom")
		(35 "F.Fab" user "Ref Des/Assembly Top")
		(33 "B.Fab" user "Ref Des/Assembly Bottom")
	)
	(footprint ""
		(layer "B.Cu")
		(at 344.461846 -90.97137 90)
		(property "Reference" "RF13"
			(at 0.8382 -0.67818 90)
			(unlocked yes)
			(layer "B.SilkS")
			(effects
				(font
					(size 0.4064 0.254)
					(thickness 0.1524)
				)
				(justify left mirror)
			)
		)
		(property "Value" ""
			(at 0 0 90)
			(layer "B.Fab")
			(effects
				(font
					(size 1.27 1.27)
				)
				(justify mirror)
			)
		)
		(duplicate_pad_numbers_are_jumpers no)
		(fp_poly
			(pts
				(xy 0.2794 -0.1016) (xy -0.2794 -0.1016) (xy -0.2794 0.9906) (xy 0.2794 0.9906)
			)
			(stroke
				(width 0)
				(type default)
			)
			(fill no)
			(layer "B.CrtYd")
		)
		(fp_line
			(start 0.2794 -0.1016)
			(end 0.2794 0.9906)
			(stroke
				(width 0.1)
				(type default)
			)
			(layer "B.Fab")
		)
		(fp_line
			(start -0.2794 -0.1016)
			(end 0.2794 -0.1016)
			(stroke
				(width 0.1)
				(type default)
			)
			(layer "B.Fab")
		)
		(fp_line
			(start 0.2794 0.9906)
			(end -0.2794 0.9906)
			(stroke
				(width 0.1)
				(type default)
			)
			(layer "B.Fab")
		)
		(fp_line
			(start -0.2794 0.9906)
			(end -0.2794 -0.1016)
			(stroke
				(width 0.1)
				(type default)
			)
			(layer "B.Fab")
		)
		(pad "1" smd rect
			(at 0 0 270)
			(size 0.508 0.508)
			(layers "B.Cu" "B.Mask" "B.Paste")
			(net "VR_PVCCIO_CPU0_AIREF1")
		)
		(pad "2" smd rect
			(at 0 0.889 270)
			(size 0.508 0.508)
			(layers "B.Cu" "B.Mask" "B.Paste")
			(net "ISENSE_PVCCIO_CPU0_PH1_IMON")
		)
		(zone
			(layer "B.Cu")
			(hatch none 0.5)
			(connect_pads
				(clearance 0)
			)
			(min_thickness 0.25)
			(keepout
				(tracks allowed)
				(vias not_allowed)
				(pads allowed)
				(copperpour not_allowed)
				(footprints allowed)
			)
			(placement
				(enabled no)
				(sheetname "")
			)
			(fill
				(thermal_gap 0.5)
				(thermal_bridge_width 0.5)
				(island_removal_mode 0)
			)
			(polygon
				(pts
					(xy 344.715846 -91.22537) (xy 344.715846 -90.71737) (xy 345.096846 -90.71737) (xy 345.096846 -91.22537)
				)
			)
		)
		(zone
			(layer "B.Cu")
			(hatch none 0.5)
			(connect_pads
				(clearance 0)
			)
			(min_thickness 0.25)
			(keepout
				(tracks not_allowed)
				(vias allowed)
				(pads allowed)
				(copperpour not_allowed)
				(footprints allowed)
			)
			(placement
				(enabled no)
				(sheetname "")
			)
			(fill
				(thermal_gap 0.5)
				(thermal_bridge_width 0.5)
				(island_removal_mode 0)
			)
			(polygon
				(pts
					(xy 345.096846 -91.22537) (xy 345.096846 -90.71737) (xy 344.715846 -90.71737) (xy 344.715846 -91.22537)
				)
			)
		)
	)
	(footprint ""
		(layer "B.Cu")
		(at 91.619324 -157.004258 90)
		(property "Reference" "C8L3"
			(at -1.47828 0.78994 180)
			(unlocked yes)
			(layer "B.SilkS")
			(effects
				(font
					(size 0.4064 0.254)
					(thickness 0.1524)
				)
				(justify mirror)
			)
		)
		(property "Value" ""
			(at 0 0 90)
			(layer "B.Fab")
			(effects
				(font
					(size 1.27 1.27)
				)
				(justify mirror)
			)
		)
		(duplicate_pad_numbers_are_jumpers no)
		(fp_poly
			(pts
				(xy 0.7239 -0.2159) (xy -0.7239 -0.2159) (xy -0.7239 1.9939) (xy 0.7239 1.9939)
			)
			(stroke
				(width 0)
				(type default)
			)
			(fill no)
			(layer "B.CrtYd")
		)
		(fp_line
			(start 0.7239 -0.2159)
			(end 0.7239 1.9939)
			(stroke
				(width 0.1)
				(type default)
			)
			(layer "B.Fab")
		)
		(fp_line
			(start -0.7239 -0.2159)
			(end 0.7239 -0.2159)
			(stroke
				(width 0.1)
				(type default)
			)
			(layer "B.Fab")
		)
		(fp_line
			(start 0.7239 1.9939)
			(end -0.7239 1.9939)
			(stroke
				(width 0.1)
				(type default)
			)
			(layer "B.Fab")
		)
		(fp_line
			(start -0.7239 1.9939)
			(end -0.7239 -0.2159)
			(stroke
				(width 0.1)
				(type default)
			)
			(layer "B.Fab")
		)
		(pad "1" smd rect
			(at 0 0 270)
			(size 1.27 1.016)
			(layers "B.Cu" "B.Mask" "B.Paste")
			(net "PVTT_KLM")
		)
		(pad "2" smd rect
			(at 0 1.778 270)
			(size 1.27 1.016)
			(layers "B.Cu" "B.Mask" "B.Paste")
			(net "GND")
		)
		(zone
			(layer "B.Cu")
			(hatch none 0.5)
			(connect_pads
				(clearance 0)
			)
			(min_thickness 0.25)
			(keepout
				(tracks not_allowed)
				(vias allowed)
				(pads allowed)
				(copperpour not_allowed)
				(footprints allowed)
			)
			(placement
				(enabled no)
				(sheetname "")
			)
			(fill
				(thermal_gap 0.5)
				(thermal_bridge_width 0.5)
				(island_removal_mode 0)
			)
			(polygon
				(pts
					(xy 92.127324 -157.639258) (xy 92.127324 -156.369258) (xy 92.889324 -156.369258) (xy 92.889324 -157.639258)
				)
			)
		)
	)
	(footprint ""
		(layer "B.Cu")
		(at 401.574 -87.3125 180)
		(property "Reference" "R2N26"
			(at 0.8382 -0.67818 180)
			(unlocked yes)
			(layer "B.SilkS")
			(effects
				(font
					(size 0.4064 0.254)
					(thickness 0.1524)
				)
				(justify left mirror)
			)
		)
		(property "Value" ""
			(at 0 0 0)
			(layer "B.Fab")
			(effects
				(font
					(size 1.27 1.27)
				)
				(justify mirror)
			)
		)
		(duplicate_pad_numbers_are_jumpers no)
		(fp_poly
			(pts
				(xy 0.2794 -0.1016) (xy -0.2794 -0.1016) (xy -0.2794 0.9906) (xy 0.2794 0.9906)
			)
			(stroke
				(width 0)
				(type default)
			)
			(fill no)
			(layer "B.CrtYd")
		)
		(fp_line
			(start 0.2794 0.9906)
			(end -0.2794 0.9906)
			(stroke
				(width 0.1)
				(type default)
			)
			(layer "B.Fab")
		)
		(fp_line
			(start 0.2794 -0.1016)
			(end 0.2794 0.9906)
			(stroke
				(width 0.1)
				(type default)
			)
			(layer "B.Fab")
		)
		(fp_line
			(start -0.2794 0.9906)
			(end -0.2794 -0.1016)
			(stroke
				(width 0.1)
				(type default)
			)
			(layer "B.Fab")
		)
		(fp_line
			(start -0.2794 -0.1016)
			(end 0.2794 -0.1016)
			(stroke
				(width 0.1)
				(type default)
			)
			(layer "B.Fab")
		)
		(pad "1" smd rect
			(at 0 0)
			(size 0.508 0.508)
			(layers "B.Cu" "B.Mask" "B.Paste")
			(net "FM_ADR_COMPLETE")
		)
		(pad "2" smd rect
			(at 0 0.889)
			(size 0.508 0.508)
			(layers "B.Cu" "B.Mask" "B.Paste")
			(net "FM_ADR_COMPLETE_R1")
		)
		(zone
			(layer "B.Cu")
			(hatch none 0.5)
			(connect_pads
				(clearance 0)
			)
			(min_thickness 0.25)
			(keepout
				(tracks not_allowed)
				(vias allowed)
				(pads allowed)
				(copperpour not_allowed)
				(footprints allowed)
			)
			(placement
				(enabled no)
				(sheetname "")
			)
			(fill
				(thermal_gap 0.5)
				(thermal_bridge_width 0.5)
				(island_removal_mode 0)
			)
			(polygon
				(pts
					(xy 401.32 -87.9475) (xy 401.828 -87.9475) (xy 401.828 -87.5665) (xy 401.32 -87.5665)
				)
			)
		)
		(zone
			(layer "B.Cu")
			(hatch none 0.5)
			(connect_pads
				(clearance 0)
			)
			(min_thickness 0.25)
			(keepout
				(tracks allowed)
				(vias not_allowed)
				(pads allowed)
				(copperpour not_allowed)
				(footprints allowed)
			)
			(placement
				(enabled no)
				(sheetname "")
			)
			(fill
				(thermal_gap 0.5)
				(thermal_bridge_width 0.5)
				(island_removal_mode 0)
			)
			(polygon
				(pts
					(xy 401.32 -87.5665) (xy 401.828 -87.5665) (xy 401.828 -87.9475) (xy 401.32 -87.9475)
				)
			)
		)
	)
	(footprint ""
		(layer "B.Cu")
		(at 130.61188 -67.764914)
		(property "Reference" "R7P25"
			(at 0 0 0)
			(layer "B.SilkS")
			(hide yes)
			(effects
				(font
					(size 1.27 1.27)
				)
				(justify mirror)
			)
		)
		(property "Value" ""
			(at 0 0 0)
			(layer "B.Fab")
			(effects
				(font
					(size 1.27 1.27)
				)
				(justify mirror)
			)
		)
		(duplicate_pad_numbers_are_jumpers no)
		(fp_poly
			(pts
				(xy 0.2794 -0.1016) (xy -0.2794 -0.1016) (xy -0.2794 0.9906) (xy 0.2794 0.9906)
			)
			(stroke
				(width 0)
				(type default)
			)
			(fill no)
			(layer "B.CrtYd")
		)
		(fp_line
			(start -0.2794 -0.1016)
			(end 0.2794 -0.1016)
			(stroke
				(width 0.1)
				(type default)
			)
			(layer "B.Fab")
		)
		(fp_line
			(start -0.2794 0.9906)
			(end -0.2794 -0.1016)
			(stroke
				(width 0.1)
				(type default)
			)
			(layer "B.Fab")
		)
		(fp_line
			(start 0.2794 -0.1016)
			(end 0.2794 0.9906)
			(stroke
				(width 0.1)
				(type default)
			)
			(layer "B.Fab")
		)
		(fp_line
			(start 0.2794 0.9906)
			(end -0.2794 0.9906)
			(stroke
				(width 0.1)
				(type default)
			)
			(layer "B.Fab")
		)
		(pad "1" smd rect
			(at 0 0 180)
			(size 0.508 0.508)
			(layers "B.Cu" "B.Mask" "B.Paste")
			(net "H_PM_SYNC_GTL_R2")
		)
		(pad "2" smd rect
			(at 0 0.889 180)
			(size 0.508 0.508)
			(layers "B.Cu" "B.Mask" "B.Paste")
			(net "H_PM_SYNC_GTL")
		)
		(zone
			(layer "B.Cu")
			(hatch none 0.5)
			(connect_pads
				(clearance 0)
			)
			(min_thickness 0.25)
			(keepout
				(tracks allowed)
				(vias not_allowed)
				(pads allowed)
				(copperpour not_allowed)
				(footprints allowed)
			)
			(placement
				(enabled no)
				(sheetname "")
			)
			(fill
				(thermal_gap 0.5)
				(thermal_bridge_width 0.5)
				(island_removal_mode 0)
			)
			(polygon
				(pts
					(xy 130.86588 -67.510914) (xy 130.35788 -67.510914) (xy 130.35788 -67.129914) (xy 130.86588 -67.129914)
				)
			)
		)
		(zone
			(layer "B.Cu")
			(hatch none 0.5)
			(connect_pads
				(clearance 0)
			)
			(min_thickness 0.25)
			(keepout
				(tracks not_allowed)
				(vias allowed)
				(pads allowed)
				(copperpour not_allowed)
				(footprints allowed)
			)
			(placement
				(enabled no)
				(sheetname "")
			)
			(fill
				(thermal_gap 0.5)
				(thermal_bridge_width 0.5)
				(island_removal_mode 0)
			)
			(polygon
				(pts
					(xy 130.86588 -67.129914) (xy 130.35788 -67.129914) (xy 130.35788 -67.510914) (xy 130.86588 -67.510914)
				)
			)
		)
	)
	(footprint ""
		(layer "B.Cu")
		(at 375.666 -101.1936 -90)
		(property "Reference" "C3N32"
			(at 0 0 90)
			(layer "B.SilkS")
			(hide yes)
			(effects
				(font
					(size 1.27 1.27)
				)
				(justify mirror)
			)
		)
		(property "Value" ""
			(at 0 0 90)
			(layer "B.Fab")
			(effects
				(font
					(size 1.27 1.27)
				)
				(justify mirror)
			)
		)
		(duplicate_pad_numbers_are_jumpers no)
		(fp_poly
			(pts
				(xy -0.3048 -0.1016) (xy -0.3048 0.9906) (xy 0.3048 0.9906) (xy 0.3048 -0.1016)
			)
			(stroke
				(width 0)
				(type default)
			)
			(fill no)
			(layer "B.CrtYd")
		)
		(fp_line
			(start -0.3048 0.9906)
			(end -0.3048 -0.1016)
			(stroke
				(width 0.1)
				(type default)
			)
			(layer "B.Fab")
		)
		(fp_line
			(start 0.3048 0.9906)
			(end -0.3048 0.9906)
			(stroke
				(width 0.1)
				(type default)
			)
			(layer "B.Fab")
		)
		(fp_line
			(start -0.3048 -0.1016)
			(end 0.3048 -0.1016)
			(stroke
				(width 0.1)
				(type default)
			)
			(layer "B.Fab")
		)
		(fp_line
			(start 0.3048 -0.1016)
			(end 0.3048 0.9906)
			(stroke
				(width 0.1)
				(type default)
			)
			(layer "B.Fab")
		)
		(pad "1" smd rect
			(at 0 0 90)
			(size 0.508 0.508)
			(layers "B.Cu" "B.Mask" "B.Paste")
			(net "RST_SRTCRST_N")
		)
		(pad "2" smd rect
			(at 0 0.889 90)
			(size 0.508 0.508)
			(layers "B.Cu" "B.Mask" "B.Paste")
			(net "GND")
		)
		(zone
			(layer "B.Cu")
			(hatch none 0.5)
			(connect_pads
				(clearance 0)
			)
			(min_thickness 0.25)
			(keepout
				(tracks not_allowed)
				(vias allowed)
				(pads allowed)
				(copperpour not_allowed)
				(footprints allowed)
			)
			(placement
				(enabled no)
				(sheetname "")
			)
			(fill
				(thermal_gap 0.5)
				(thermal_bridge_width 0.5)
				(island_removal_mode 0)
			)
			(polygon
				(pts
					(xy 375.031 -100.9396) (xy 375.031 -101.4476) (xy 375.412 -101.4476) (xy 375.412 -100.9396)
				)
			)
		)
		(zone
			(layer "B.Cu")
			(hatch none 0.5)
			(connect_pads
				(clearance 0)
			)
			(min_thickness 0.25)
			(keepout
				(tracks allowed)
				(vias not_allowed)
				(pads allowed)
				(copperpour not_allowed)
				(footprints allowed)
			)
			(placement
				(enabled no)
				(sheetname "")
			)
			(fill
				(thermal_gap 0.5)
				(thermal_bridge_width 0.5)
				(island_removal_mode 0)
			)
			(polygon
				(pts
					(xy 375.412 -100.9396) (xy 375.412 -101.4476) (xy 375.031 -101.4476) (xy 375.031 -100.9396)
				)
			)
		)
	)
	(footprint ""
		(layer "B.Cu")
		(at 362.671614 -125.558042 -90)
		(property "Reference" "C3M28"
			(at 0 0 90)
			(layer "B.SilkS")
			(hide yes)
			(effects
				(font
					(size 1.27 1.27)
				)
				(justify mirror)
			)
		)
		(property "Value" ""
			(at 0 0 90)
			(layer "B.Fab")
			(effects
				(font
					(size 1.27 1.27)
				)
				(justify mirror)
			)
		)
		(duplicate_pad_numbers_are_jumpers no)
		(fp_poly
			(pts
				(xy -0.3048 -0.1016) (xy -0.3048 0.9906) (xy 0.3048 0.9906) (xy 0.3048 -0.1016)
			)
			(stroke
				(width 0)
				(type default)
			)
			(fill no)
			(layer "B.CrtYd")
		)
		(fp_line
			(start -0.3048 0.9906)
			(end -0.3048 -0.1016)
			(stroke
				(width 0.1)
				(type default)
			)
			(layer "B.Fab")
		)
		(fp_line
			(start 0.3048 0.9906)
			(end -0.3048 0.9906)
			(stroke
				(width 0.1)
				(type default)
			)
			(layer "B.Fab")
		)
		(fp_line
			(start -0.3048 -0.1016)
			(end 0.3048 -0.1016)
			(stroke
				(width 0.1)
				(type default)
			)
			(layer "B.Fab")
		)
		(fp_line
			(start 0.3048 -0.1016)
			(end 0.3048 0.9906)
			(stroke
				(width 0.1)
				(type default)
			)
			(layer "B.Fab")
		)
		(pad "1" smd rect
			(at 0 0 90)
			(size 0.508 0.508)
			(layers "B.Cu" "B.Mask" "B.Paste")
			(net "P3E_CPU0_PE1_PCH_R_RXP<10>")
		)
		(pad "2" smd rect
			(at 0 0.889 90)
			(size 0.508 0.508)
			(layers "B.Cu" "B.Mask" "B.Paste")
			(net "P3E_CPU0_PE1_PCH_RXP<10>")
		)
		(zone
			(layer "B.Cu")
			(hatch none 0.5)
			(connect_pads
				(clearance 0)
			)
			(min_thickness 0.25)
			(keepout
				(tracks not_allowed)
				(vias allowed)
				(pads allowed)
				(copperpour not_allowed)
				(footprints allowed)
			)
			(placement
				(enabled no)
				(sheetname "")
			)
			(fill
				(thermal_gap 0.5)
				(thermal_bridge_width 0.5)
				(island_removal_mode 0)
			)
			(polygon
				(pts
					(xy 362.036614 -125.304042) (xy 362.036614 -125.812042) (xy 362.417614 -125.812042) (xy 362.417614 -125.304042)
				)
			)
		)
		(zone
			(layer "B.Cu")
			(hatch none 0.5)
			(connect_pads
				(clearance 0)
			)
			(min_thickness 0.25)
			(keepout
				(tracks allowed)
				(vias not_allowed)
				(pads allowed)
				(copperpour not_allowed)
				(footprints allowed)
			)
			(placement
				(enabled no)
				(sheetname "")
			)
			(fill
				(thermal_gap 0.5)
				(thermal_bridge_width 0.5)
				(island_removal_mode 0)
			)
			(polygon
				(pts
					(xy 362.417614 -125.304042) (xy 362.417614 -125.812042) (xy 362.036614 -125.812042) (xy 362.036614 -125.304042)
				)
			)
		)
	)
	(footprint ""
		(layer "B.Cu")
		(at 394.335 -65.3415 90)
		(property "Reference" "R2T9"
			(at 0 0 90)
			(layer "B.SilkS")
			(hide yes)
			(effects
				(font
					(size 1.27 1.27)
				)
				(justify mirror)
			)
		)
		(property "Value" ""
			(at 0 0 90)
			(layer "B.Fab")
			(effects
				(font
					(size 1.27 1.27)
				)
				(justify mirror)
			)
		)
		(duplicate_pad_numbers_are_jumpers no)
		(fp_poly
			(pts
				(xy 0.2794 -0.1016) (xy -0.2794 -0.1016) (xy -0.2794 0.9906) (xy 0.2794 0.9906)
			)
			(stroke
				(width 0)
				(type default)
			)
			(fill no)
			(layer "B.CrtYd")
		)
		(fp_line
			(start 0.2794 -0.1016)
			(end 0.2794 0.9906)
			(stroke
				(width 0.1)
				(type default)
			)
			(layer "B.Fab")
		)
		(fp_line
			(start -0.2794 -0.1016)
			(end 0.2794 -0.1016)
			(stroke
				(width 0.1)
				(type default)
			)
			(layer "B.Fab")
		)
		(fp_line
			(start 0.2794 0.9906)
			(end -0.2794 0.9906)
			(stroke
				(width 0.1)
				(type default)
			)
			(layer "B.Fab")
		)
		(fp_line
			(start -0.2794 0.9906)
			(end -0.2794 -0.1016)
			(stroke
				(width 0.1)
				(type default)
			)
			(layer "B.Fab")
		)
		(pad "1" smd rect
			(at 0 0 270)
			(size 0.508 0.508)
			(layers "B.Cu" "B.Mask" "B.Paste")
			(net "SPI_CS0_SECONDARY_N")
		)
		(pad "2" smd rect
			(at 0 0.889 270)
			(size 0.508 0.508)
			(layers "B.Cu" "B.Mask" "B.Paste")
			(net "SPI_CS0_SECONDARY_R_N")
		)
		(zone
			(layer "B.Cu")
			(hatch none 0.5)
			(connect_pads
				(clearance 0)
			)
			(min_thickness 0.25)
			(keepout
				(tracks allowed)
				(vias not_allowed)
				(pads allowed)
				(copperpour not_allowed)
				(footprints allowed)
			)
			(placement
				(enabled no)
				(sheetname "")
			)
			(fill
				(thermal_gap 0.5)
				(thermal_bridge_width 0.5)
				(island_removal_mode 0)
			)
			(polygon
				(pts
					(xy 394.589 -65.5955) (xy 394.589 -65.0875) (xy 394.97 -65.0875) (xy 394.97 -65.5955)
				)
			)
		)
		(zone
			(layer "B.Cu")
			(hatch none 0.5)
			(connect_pads
				(clearance 0)
			)
			(min_thickness 0.25)
			(keepout
				(tracks not_allowed)
				(vias allowed)
				(pads allowed)
				(copperpour not_allowed)
				(footprints allowed)
			)
			(placement
				(enabled no)
				(sheetname "")
			)
			(fill
				(thermal_gap 0.5)
				(thermal_bridge_width 0.5)
				(island_removal_mode 0)
			)
			(polygon
				(pts
					(xy 394.97 -65.5955) (xy 394.97 -65.0875) (xy 394.589 -65.0875) (xy 394.589 -65.5955)
				)
			)
		)
	)
)
